FILE_TYPE = MACRO_DRAWING;
SET COLOR_WIRE YELLOW;
SET COLOR_PROP MONO;
SET COLOR_DOT WHITE;
SET COLOR_ARC YELLOW;
SET COLOR_BODY GREEN;
SET COLOR_NOTE MONO;
SET PROP_DISPLAY VALUE;
SET PAGE_NUMBER P69;
FORCEADD SKX_EXT_B..15
(-4275 2700);
FORCEPROP 1 LAST LOCATION U2D1
J 0
(-5025 3950);
DISPLAY 0.617021 (-5025 3950);
PAINT AQUA (-5025 3950);
FORCEPROP 1 LAST PART_NUMBER TBD
J 0
(-5025 1500);
DISPLAY 0.617021 (-5025 1500);
PAINT BLUE (-5025 1500);
FORCEPROP 2 LASTPIN (-3475 3700) $PN CA12
J 0
(-3465 3710);
DISPLAY 0.617021 (-3465 3710);
PAINT ORANGE (-3465 3710);
FORCEPROP 2 LASTPIN (-3475 3650) $PN CB11
J 0
(-3465 3660);
DISPLAY 0.617021 (-3465 3660);
PAINT ORANGE (-3465 3660);
FORCEPROP 2 LASTPIN (-3475 3600) $PN CD11
J 0
(-3465 3610);
DISPLAY 0.617021 (-3465 3610);
PAINT ORANGE (-3465 3610);
FORCEPROP 2 LASTPIN (-3475 3550) $PN CF11
J 0
(-3465 3560);
DISPLAY 0.617021 (-3465 3560);
PAINT ORANGE (-3465 3560);
FORCEPROP 2 LASTPIN (-3475 3500) $PN CG12
J 0
(-3465 3510);
DISPLAY 0.617021 (-3465 3510);
PAINT ORANGE (-3465 3510);
FORCEPROP 2 LASTPIN (-3475 3450) $PN CH13
J 0
(-3465 3460);
DISPLAY 0.617021 (-3465 3460);
PAINT ORANGE (-3465 3460);
FORCEPROP 2 LASTPIN (-3475 3400) $PN CK13
J 0
(-3465 3410);
DISPLAY 0.617021 (-3465 3410);
PAINT ORANGE (-3465 3410);
FORCEPROP 2 LASTPIN (-3475 3350) $PN CR14
J 0
(-3465 3360);
DISPLAY 0.617021 (-3465 3360);
PAINT ORANGE (-3465 3360);
FORCEPROP 2 LASTPIN (-3475 3300) $PN CV13
J 0
(-3465 3310);
DISPLAY 0.617021 (-3465 3310);
PAINT ORANGE (-3465 3310);
FORCEPROP 2 LASTPIN (-3475 3250) $PN CW16
J 0
(-3465 3260);
DISPLAY 0.617021 (-3465 3260);
PAINT ORANGE (-3465 3260);
FORCEPROP 2 LASTPIN (-3475 3200) $PN DB15
J 0
(-3465 3210);
DISPLAY 0.617021 (-3465 3210);
PAINT ORANGE (-3465 3210);
FORCEPROP 2 LASTPIN (-3475 3150) $PN DD15
J 0
(-3465 3160);
DISPLAY 0.617021 (-3465 3160);
PAINT ORANGE (-3465 3160);
FORCEPROP 2 LASTPIN (-3475 3100) $PN DE16
J 0
(-3465 3110);
DISPLAY 0.617021 (-3465 3110);
PAINT ORANGE (-3465 3110);
FORCEPROP 2 LASTPIN (-3475 3000) $PN DH17
J 0
(-3465 3010);
DISPLAY 0.617021 (-3465 3010);
PAINT ORANGE (-3465 3010);
FORCEPROP 2 LASTPIN (-3475 2950) $PN DJ18
J 0
(-3465 2960);
DISPLAY 0.617021 (-3465 2960);
PAINT ORANGE (-3465 2960);
FORCEPROP 2 LASTPIN (-3475 2900) $PN DJ20
J 0
(-3465 2910);
DISPLAY 0.617021 (-3465 2910);
PAINT ORANGE (-3465 2910);
FORCEPROP 2 LASTPIN (-3475 2850) $PN DK19
J 0
(-3465 2860);
DISPLAY 0.617021 (-3465 2860);
PAINT ORANGE (-3465 2860);
FORCEPROP 2 LASTPIN (-3475 2800) $PN DN20
J 0
(-3465 2810);
DISPLAY 0.617021 (-3465 2810);
PAINT ORANGE (-3465 2810);
FORCEPROP 2 LASTPIN (-3475 2750) $PN DP21
J 0
(-3465 2760);
DISPLAY 0.617021 (-3465 2760);
PAINT ORANGE (-3465 2760);
FORCEPROP 2 LASTPIN (-3475 2650) $PN CC12
J 0
(-3465 2660);
DISPLAY 0.617021 (-3465 2660);
PAINT ORANGE (-3465 2660);
FORCEPROP 2 LASTPIN (-3475 2600) $PN CC10
J 0
(-3465 2610);
DISPLAY 0.617021 (-3465 2610);
PAINT ORANGE (-3465 2610);
FORCEPROP 2 LASTPIN (-3475 2550) $PN CE12
J 0
(-3465 2560);
DISPLAY 0.617021 (-3465 2560);
PAINT ORANGE (-3465 2560);
FORCEPROP 2 LASTPIN (-3475 2500) $PN CH11
J 0
(-3465 2510);
DISPLAY 0.617021 (-3465 2510);
PAINT ORANGE (-3465 2510);
FORCEPROP 2 LASTPIN (-3475 2450) $PN CF13
J 0
(-3465 2460);
DISPLAY 0.617021 (-3465 2460);
PAINT ORANGE (-3465 2460);
FORCEPROP 2 LASTPIN (-3475 2400) $PN CJ14
J 0
(-3465 2410);
DISPLAY 0.617021 (-3465 2410);
PAINT ORANGE (-3465 2410);
FORCEPROP 2 LASTPIN (-3475 2350) $PN CM13
J 0
(-3465 2360);
DISPLAY 0.617021 (-3465 2360);
PAINT ORANGE (-3465 2360);
FORCEPROP 2 LASTPIN (-3475 2300) $PN CU14
J 0
(-3465 2310);
DISPLAY 0.617021 (-3465 2310);
PAINT ORANGE (-3465 2310);
FORCEPROP 2 LASTPIN (-3475 2250) $PN CW14
J 0
(-3465 2260);
DISPLAY 0.617021 (-3465 2260);
PAINT ORANGE (-3465 2260);
FORCEPROP 2 LASTPIN (-3475 2200) $PN DA16
J 0
(-3465 2210);
DISPLAY 0.617021 (-3465 2210);
PAINT ORANGE (-3465 2210);
FORCEPROP 2 LASTPIN (-3475 2150) $PN DC16
J 0
(-3465 2160);
DISPLAY 0.617021 (-3465 2160);
PAINT ORANGE (-3465 2160);
FORCEPROP 2 LASTPIN (-3475 2100) $PN DF15
J 0
(-3465 2110);
DISPLAY 0.617021 (-3465 2110);
PAINT ORANGE (-3465 2110);
FORCEPROP 2 LASTPIN (-3475 2050) $PN DD17
J 0
(-3465 2060);
DISPLAY 0.617021 (-3465 2060);
PAINT ORANGE (-3465 2060);
FORCEPROP 2 LASTPIN (-3475 2000) $PN DG18
J 0
(-3465 2010);
DISPLAY 0.617021 (-3465 2010);
PAINT ORANGE (-3465 2010);
FORCEPROP 2 LASTPIN (-3475 1950) $PN DK17
J 0
(-3465 1960);
DISPLAY 0.617021 (-3465 1960);
PAINT ORANGE (-3465 1960);
FORCEPROP 2 LASTPIN (-3475 1900) $PN DH19
J 0
(-3465 1910);
DISPLAY 0.617021 (-3465 1910);
PAINT ORANGE (-3465 1910);
FORCEPROP 2 LASTPIN (-3475 1850) $PN DG20
J 0
(-3465 1860);
DISPLAY 0.617021 (-3465 1860);
PAINT ORANGE (-3465 1860);
FORCEPROP 2 LASTPIN (-3475 1800) $PN DL20
J 0
(-3465 1810);
DISPLAY 0.617021 (-3465 1810);
PAINT ORANGE (-3465 1810);
FORCEPROP 2 LASTPIN (-3475 1750) $PN DM21
J 0
(-3465 1760);
DISPLAY 0.617021 (-3465 1760);
PAINT ORANGE (-3465 1760);
FORCEPROP 2 LASTPIN (-3475 1700) $PN DT21
J 0
(-3465 1710);
DISPLAY 0.617021 (-3465 1710);
PAINT ORANGE (-3465 1710);
FORCEPROP 2 LASTPIN (-5075 3700) $PN CA16
J 2
(-5085 3710);
DISPLAY 0.617021 (-5085 3710);
PAINT ORANGE (-5085 3710);
FORCEPROP 2 LASTPIN (-5075 3650) $PN BY15
J 2
(-5085 3660);
DISPLAY 0.617021 (-5085 3660);
PAINT ORANGE (-5085 3660);
FORCEPROP 2 LASTPIN (-5075 3600) $PN CD17
J 2
(-5085 3610);
DISPLAY 0.617021 (-5085 3610);
PAINT ORANGE (-5085 3610);
FORCEPROP 2 LASTPIN (-5075 3550) $PN CC14
J 2
(-5085 3560);
DISPLAY 0.617021 (-5085 3560);
PAINT ORANGE (-5085 3560);
FORCEPROP 2 LASTPIN (-5075 3500) $PN CF15
J 2
(-5085 3510);
DISPLAY 0.617021 (-5085 3510);
PAINT ORANGE (-5085 3510);
FORCEPROP 2 LASTPIN (-5075 3450) $PN CG16
J 2
(-5085 3460);
DISPLAY 0.617021 (-5085 3460);
PAINT ORANGE (-5085 3460);
FORCEPROP 2 LASTPIN (-5075 3400) $PN CK17
J 2
(-5085 3410);
DISPLAY 0.617021 (-5085 3410);
PAINT ORANGE (-5085 3410);
FORCEPROP 2 LASTPIN (-5075 3350) $PN CJ16
J 2
(-5085 3360);
DISPLAY 0.617021 (-5085 3360);
PAINT ORANGE (-5085 3360);
FORCEPROP 2 LASTPIN (-5075 3300) $PN CM21
J 2
(-5085 3310);
DISPLAY 0.617021 (-5085 3310);
PAINT ORANGE (-5085 3310);
FORCEPROP 2 LASTPIN (-5075 3250) $PN CP19
J 2
(-5085 3260);
DISPLAY 0.617021 (-5085 3260);
PAINT ORANGE (-5085 3260);
FORCEPROP 2 LASTPIN (-5075 3200) $PN CN18
J 2
(-5085 3210);
DISPLAY 0.617021 (-5085 3210);
PAINT ORANGE (-5085 3210);
FORCEPROP 2 LASTPIN (-5075 3150) $PN CR20
J 2
(-5085 3160);
DISPLAY 0.617021 (-5085 3160);
PAINT ORANGE (-5085 3160);
FORCEPROP 2 LASTPIN (-5075 3100) $PN CW18
J 2
(-5085 3110);
DISPLAY 0.617021 (-5085 3110);
PAINT ORANGE (-5085 3110);
FORCEPROP 2 LASTPIN (-5075 3050) $PN CU20
J 2
(-5085 3060);
DISPLAY 0.617021 (-5085 3060);
PAINT ORANGE (-5085 3060);
FORCEPROP 2 LASTPIN (-5075 3000) $PN CY19
J 2
(-5085 3010);
DISPLAY 0.617021 (-5085 3010);
PAINT ORANGE (-5085 3010);
FORCEPROP 2 LASTPIN (-5075 2850) $PN DA22
J 2
(-5085 2860);
DISPLAY 0.617021 (-5085 2860);
PAINT ORANGE (-5085 2860);
FORCEPROP 2 LASTPIN (-5075 2800) $PN DD21
J 2
(-5085 2810);
DISPLAY 0.617021 (-5085 2810);
PAINT ORANGE (-5085 2810);
FORCEPROP 2 LASTPIN (-5075 2750) $PN DG22
J 2
(-5085 2760);
DISPLAY 0.617021 (-5085 2760);
PAINT ORANGE (-5085 2760);
FORCEPROP 2 LASTPIN (-5075 2650) $PN BY17
J 2
(-5085 2660);
DISPLAY 0.617021 (-5085 2660);
PAINT ORANGE (-5085 2660);
FORCEPROP 2 LASTPIN (-5075 2600) $PN CB15
J 2
(-5085 2610);
DISPLAY 0.617021 (-5085 2610);
PAINT ORANGE (-5085 2610);
FORCEPROP 2 LASTPIN (-5075 2550) $PN CF17
J 2
(-5085 2560);
DISPLAY 0.617021 (-5085 2560);
PAINT ORANGE (-5085 2560);
FORCEPROP 2 LASTPIN (-5075 2500) $PN CD15
J 2
(-5085 2510);
DISPLAY 0.617021 (-5085 2510);
PAINT ORANGE (-5085 2510);
FORCEPROP 2 LASTPIN (-5075 2450) $PN CE16
J 2
(-5085 2460);
DISPLAY 0.617021 (-5085 2460);
PAINT ORANGE (-5085 2460);
FORCEPROP 2 LASTPIN (-5075 2400) $PN CH17
J 2
(-5085 2410);
DISPLAY 0.617021 (-5085 2410);
PAINT ORANGE (-5085 2410);
FORCEPROP 2 LASTPIN (-5075 2350) $PN CJ18
J 2
(-5085 2360);
DISPLAY 0.617021 (-5085 2360);
PAINT ORANGE (-5085 2360);
FORCEPROP 2 LASTPIN (-5075 2300) $PN CL16
J 2
(-5085 2310);
DISPLAY 0.617021 (-5085 2310);
PAINT ORANGE (-5085 2310);
FORCEPROP 2 LASTPIN (-5075 2250) $PN CP21
J 2
(-5085 2260);
DISPLAY 0.617021 (-5085 2260);
PAINT ORANGE (-5085 2260);
FORCEPROP 2 LASTPIN (-5075 2200) $PN CN20
J 2
(-5085 2210);
DISPLAY 0.617021 (-5085 2210);
PAINT ORANGE (-5085 2210);
FORCEPROP 2 LASTPIN (-5075 2150) $PN CR18
J 2
(-5085 2160);
DISPLAY 0.617021 (-5085 2160);
PAINT ORANGE (-5085 2160);
FORCEPROP 2 LASTPIN (-5075 2100) $PN CT21
J 2
(-5085 2110);
DISPLAY 0.617021 (-5085 2110);
PAINT ORANGE (-5085 2110);
FORCEPROP 2 LASTPIN (-5075 2050) $PN CV19
J 2
(-5085 2060);
DISPLAY 0.617021 (-5085 2060);
PAINT ORANGE (-5085 2060);
FORCEPROP 2 LASTPIN (-5075 2000) $PN CW20
J 2
(-5085 2010);
DISPLAY 0.617021 (-5085 2010);
PAINT ORANGE (-5085 2010);
FORCEPROP 2 LASTPIN (-5075 1950) $PN DA20
J 2
(-5085 1960);
DISPLAY 0.617021 (-5085 1960);
PAINT ORANGE (-5085 1960);
FORCEPROP 2 LASTPIN (-5075 1900) $PN DD19
J 2
(-5085 1910);
DISPLAY 0.617021 (-5085 1910);
PAINT ORANGE (-5085 1910);
FORCEPROP 2 LASTPIN (-5075 1850) $PN DB21
J 2
(-5085 1860);
DISPLAY 0.617021 (-5085 1860);
PAINT ORANGE (-5085 1860);
FORCEPROP 2 LASTPIN (-5075 1800) $PN DC22
J 2
(-5085 1810);
DISPLAY 0.617021 (-5085 1810);
PAINT ORANGE (-5085 1810);
FORCEPROP 2 LASTPIN (-5075 1750) $PN DE22
J 2
(-5085 1760);
DISPLAY 0.617021 (-5085 1760);
PAINT ORANGE (-5085 1760);
FORCEPROP 2 LASTPIN (-5075 1700) $PN DF23
J 2
(-5085 1710);
DISPLAY 0.617021 (-5085 1710);
PAINT ORANGE (-5085 1710);
FORCEPROP 2 LASTPIN (-5075 2950) $PN DB19
J 2
(-5085 2960);
DISPLAY 0.617021 (-5085 2960);
PAINT ORANGE (-5085 2960);
FORCEPROP 2 LASTPIN (-5075 2900) $PN DC20
J 2
(-5085 2910);
DISPLAY 0.617021 (-5085 2910);
PAINT ORANGE (-5085 2910);
FORCEPROP 2 LASTPIN (-3475 3050) $PN DF17
J 0
(-3465 3060);
DISPLAY 0.617021 (-3465 3060);
PAINT ORANGE (-3465 3060);
FORCEPROP 1 LAST MATERIAL IC
J 0
(-5025 3900);
DISPLAY 0.617021 (-5025 3900);
PAINT SKYBLUE (-5025 3900);
FORCEPROP 1 LAST PACK_TYPE BGA1
J 0
(-5025 4000);
PAINT SKYBLUE (-5025 4000);
DISPLAY INVISIBLE (-5025 4000);
FORCEPROP 2 LAST SEC_TYPE BGA1
J 0
(-5025 4000);
DISPLAY 1.021277 (-5025 4000);
PAINT ORANGE (-5025 4000);
DISPLAY INVISIBLE (-5025 4000);
FORCEPROP 2 LAST CDS_LIB chpset_lib
J 0
(-4275 2700);
PAINT ORANGE (-4275 2700);
DISPLAY INVISIBLE (-4275 2700);
FORCEPROP 2 LAST SEC 15
J 0
(-5025 4000);
DISPLAY 0.680851 (-5025 4000);
PAINT MONO (-5025 4000);
DISPLAY INVISIBLE (-5025 4000);
FORCEPROP 2 LAST CDS_LOCATION U2D1
J 0
(-5025 3950);
DISPLAY 0.617021 (-5025 3950);
PAINT AQUA (-5025 3950);
DISPLAY INVISIBLE (-5025 3950);
FORCEPROP 1 LAST PATH I1
J 0
(-4275 3900);
PAINT GREEN (-4275 3900);
DISPLAY INVISIBLE (-4275 3900);
FORCEADD GND..1
(-6025 1475);
FORCEPROP 3 LASTPIN (-6025 1525) SIG_NAME GND\g
J 0
(-6015 1535);
DISPLAY 0.659574 (-6015 1535);
PAINT MONO (-6015 1535);
DISPLAY INVISIBLE (-6015 1535);
FORCEPROP 1 LAST VOLTAGE 0.0V
J 0
(-6070 1432);
DISPLAY 0.340426 (-6070 1432);
PAINT SKYBLUE (-6070 1432);
DISPLAY INVISIBLE (-6070 1432);
FORCEPROP 1 LAST SIZE 1B
J 0
(-5950 1425);
DISPLAY 1.170213 (-5950 1425);
PAINT AQUA (-5950 1425);
DISPLAY INVISIBLE (-5950 1425);
FORCEPROP 2 LAST CDS_LIB mstr_symbols
J 0
(-6025 1475);
PAINT MONO (-6025 1475);
DISPLAY INVISIBLE (-6025 1475);
FORCEPROP 1 LAST BODY_TYPE PLUMBING
J 0
(-6070 1432);
DISPLAY 0.340426 (-6070 1432);
PAINT GREEN (-6070 1432);
DISPLAY INVISIBLE (-6070 1432);
FORCEPROP 1 LAST PATH I2
J 0
(-5950 1475);
DISPLAY 0.872340 (-5950 1475);
PAINT AQUA (-5950 1475);
DISPLAY INVISIBLE (-5950 1475);
FORCEPROP 1 LAST HDL_POWER GND
J 0
(-6025 1625);
DISPLAY 1.170213 (-6025 1625);
PAINT GREEN (-6025 1625);
DISPLAY INVISIBLE (-6025 1625);
FORCEADD DESIGN_NOTE..1
(-4825 1400);
FORCEPROP 0 LAST L1 CPU SYMBOLS 1-30 ARE PRELIMINARY AND SUBJECT TO CHANGE
J 0
(-5025 1275);
DISPLAY 1.021277 (-5025 1275);
PAINT ORANGE (-5025 1275);
FORCEPROP 2 LAST CDS_LIB mstr_symbols
J 0
(-4825 1400);
PAINT ORANGE (-4825 1400);
DISPLAY INVISIBLE (-4825 1400);
FORCEPROP 1 LAST COMMENT_BODY TRUE
J 0
(-4800 1500);
DISPLAY 0.978723 (-4800 1500);
PAINT ORANGE (-4800 1500);
DISPLAY INVISIBLE (-4800 1500);
FORCEADD PRELIM..10
(-4265 2690);
PAINT GRAY (-4265 2690);
FORCEPROP 2 LAST CDS_LIB mstr_misc
J 0
(-4265 2690);
PAINT ORANGE (-4265 2690);
DISPLAY INVISIBLE (-4265 2690);
FORCEPROP 1 LAST COMMENT_BODY TRUE
J 0
(-4265 2690);
PAINT ORANGE (-4265 2690);
DISPLAY INVISIBLE (-4265 2690);
FORCEADD INTEL_CORP_BPAGE..1
(0 0);
FORCEPROP 1 LAST CDS_CON_LAST_MODIFIED Fri Jun 16 17:48:26 2017
J 0
(-1425 325);
DISPLAY 1.340426 (-1425 325);
PAINT GREEN (-1425 325);
DISPLAY INVISIBLE (-1425 325);
FORCEPROP 1 LAST CUSTOM_TXT_CDS <CURRENT_DESIGN_SHEET> OF <TOTAL_DESIGN_SHEETS>
J 0
(-500 25);
PAINT ORANGE (-500 25);
FORCEPROP 1 LAST CUSTOM_TXT_CDS <CON_LAST_MODIFIED>
J 0
(-4000 100);
PAINT ORANGE (-4000 100);
FORCEPROP 2 LAST CUSTOM_TXT_CDS <XR_PAGE_TITLE>
J 0
(-7890 5250);
DISPLAY 0.638298 (-7890 5250);
PAINT PINK (-7890 5250);
DISPLAY INVISIBLE (-7890 5250);
FORCEPROP 1 LAST SCH_TITLE SKYLAKE - SKT1 - 15 OF 21
J 0
(-7950 50);
DISPLAY 1.212766 (-7950 50);
PAINT GREEN (-7950 50);
FORCEPROP 2 LAST CDS_LIB mstr_symbols
J 0
(0 0);
PAINT ORANGE (0 0);
DISPLAY INVISIBLE (0 0);
FORCEPROP 2 LAST PAGE_BORDER TRUE
J 0
(-7890 5250);
DISPLAY 0.851064 (-7890 5250);
PAINT PINK (-7890 5250);
DISPLAY INVISIBLE (-7890 5250);
FORCEPROP 1 LAST COMMENT_BODY TRUE
J 0
(12 12);
DISPLAY 0.638298 (12 12);
PAINT GREEN (12 12);
DISPLAY INVISIBLE (12 12);
FORCEPROP 2 LAST CDS_XR_PAGE_TITLE CR-69 : @BASEBOARD_FAB2_LIB.BASEBOARD_FAB2(SCH_1):PAGE69
J 0
(-7890 5250);
DISPLAY 0.638298 (-7890 5250);
PAINT PINK (-7890 5250);
DISPLAY INVISIBLE (-7890 5250);
WIRE 16 -1 (-6025 1700)(-6025 1525);
WIRE 16 -1 (-6025 1750)(-6025 1700);
WIRE 16 -1 (-5075 1700)(-6025 1700);
WIRE 16 -1 (-6025 1800)(-6025 1750);
WIRE 16 -1 (-5075 1750)(-6025 1750);
WIRE 16 -1 (-6025 1850)(-6025 1800);
WIRE 16 -1 (-5075 1800)(-6025 1800);
WIRE 16 -1 (-6025 1900)(-6025 1850);
WIRE 16 -1 (-5075 1850)(-6025 1850);
WIRE 16 -1 (-6025 1950)(-6025 1900);
WIRE 16 -1 (-5075 1900)(-6025 1900);
WIRE 16 -1 (-6025 2000)(-6025 1950);
WIRE 16 -1 (-5075 1950)(-6025 1950);
WIRE 16 -1 (-6025 2050)(-6025 2000);
WIRE 16 -1 (-5075 2000)(-6025 2000);
WIRE 16 -1 (-6025 2100)(-6025 2050);
WIRE 16 -1 (-5075 2050)(-6025 2050);
WIRE 16 -1 (-6025 2150)(-6025 2100);
WIRE 16 -1 (-5075 2100)(-6025 2100);
WIRE 16 -1 (-6025 2200)(-6025 2150);
WIRE 16 -1 (-5075 2150)(-6025 2150);
WIRE 16 -1 (-6025 2250)(-6025 2200);
WIRE 16 -1 (-5075 2200)(-6025 2200);
WIRE 16 -1 (-6025 2300)(-6025 2250);
WIRE 16 -1 (-5075 2250)(-6025 2250);
WIRE 16 -1 (-6025 2350)(-6025 2300);
WIRE 16 -1 (-5075 2300)(-6025 2300);
WIRE 16 -1 (-6025 2400)(-6025 2350);
WIRE 16 -1 (-5075 2350)(-6025 2350);
WIRE 16 -1 (-6025 2450)(-6025 2400);
WIRE 16 -1 (-5075 2400)(-6025 2400);
WIRE 16 -1 (-6025 2500)(-6025 2450);
WIRE 16 -1 (-5075 2450)(-6025 2450);
WIRE 16 -1 (-6025 2550)(-6025 2500);
WIRE 16 -1 (-5075 2500)(-6025 2500);
WIRE 16 -1 (-6025 2600)(-6025 2550);
WIRE 16 -1 (-5075 2550)(-6025 2550);
WIRE 16 -1 (-6025 2650)(-6025 2600);
WIRE 16 -1 (-5075 2600)(-6025 2600);
WIRE 16 -1 (-6025 2750)(-6025 2650);
WIRE 16 -1 (-5075 2650)(-6025 2650);
WIRE 16 -1 (-6025 2800)(-6025 2750);
WIRE 16 -1 (-5075 2750)(-6025 2750);
WIRE 16 -1 (-6025 2850)(-6025 2800);
WIRE 16 -1 (-5075 2800)(-6025 2800);
WIRE 16 -1 (-6025 2900)(-6025 2850);
WIRE 16 -1 (-5075 2850)(-6025 2850);
WIRE 16 -1 (-6025 2950)(-6025 2900);
WIRE 16 -1 (-5075 2900)(-6025 2900);
WIRE 16 -1 (-6025 3000)(-6025 2950);
WIRE 16 -1 (-5075 2950)(-6025 2950);
WIRE 16 -1 (-6025 3050)(-6025 3000);
WIRE 16 -1 (-5075 3000)(-6025 3000);
WIRE 16 -1 (-6025 3100)(-6025 3050);
WIRE 16 -1 (-5075 3050)(-6025 3050);
WIRE 16 -1 (-6025 3150)(-6025 3100);
WIRE 16 -1 (-5075 3100)(-6025 3100);
WIRE 16 -1 (-6025 3200)(-6025 3150);
WIRE 16 -1 (-5075 3150)(-6025 3150);
WIRE 16 -1 (-6025 3250)(-6025 3200);
WIRE 16 -1 (-5075 3200)(-6025 3200);
WIRE 16 -1 (-6025 3300)(-6025 3250);
WIRE 16 -1 (-5075 3250)(-6025 3250);
WIRE 16 -1 (-6025 3350)(-6025 3300);
WIRE 16 -1 (-5075 3300)(-6025 3300);
WIRE 16 -1 (-6025 3400)(-6025 3350);
WIRE 16 -1 (-5075 3350)(-6025 3350);
WIRE 16 -1 (-6025 3450)(-6025 3400);
WIRE 16 -1 (-5075 3400)(-6025 3400);
WIRE 16 -1 (-6025 3500)(-6025 3450);
WIRE 16 -1 (-5075 3450)(-6025 3450);
WIRE 16 -1 (-6025 3550)(-6025 3500);
WIRE 16 -1 (-5075 3500)(-6025 3500);
WIRE 16 -1 (-6025 3600)(-6025 3550);
WIRE 16 -1 (-5075 3550)(-6025 3550);
WIRE 16 -1 (-6025 3650)(-6025 3600);
WIRE 16 -1 (-5075 3600)(-6025 3600);
WIRE 16 -1 (-6025 3700)(-6025 3650);
WIRE 16 -1 (-5075 3650)(-6025 3650);
WIRE 16 -1 (-5075 3700)(-6025 3700);
WIRE 16 -1 (-2525 3100)(-3475 3100);
FORCEPROP 0 LAST SIG_NAME TP_CPU1_UPI2_RSVD_CR14
J 0
(-3125 3110);
DISPLAY 0.617021 (-3125 3110);
PAINT ORANGE (-3125 3110);
FORCEPROP 2 LASTPROP $XRERR UNIQUE?
J 0
(-2495 3100);
DISPLAY 0.638298 (-2495 3100);
PAINT MONO (-2495 3100);
DISPLAY INVISIBLE (-2495 3100);
WIRE 16 -1 (-2525 1700)(-3475 1700);
FORCEPROP 0 LAST SIG_NAME TP_CPU1_UPI2_RSVD_CC12
J 0
(-3125 1710);
DISPLAY 0.617021 (-3125 1710);
PAINT ORANGE (-3125 1710);
FORCEPROP 2 LASTPROP $XRERR UNIQUE?
J 0
(-2495 1700);
DISPLAY 0.638298 (-2495 1700);
PAINT MONO (-2495 1700);
DISPLAY INVISIBLE (-2495 1700);
WIRE 16 -1 (-2525 1750)(-3475 1750);
FORCEPROP 0 LAST SIG_NAME TP_CPU1_UPI2_RSVD_CC10
J 0
(-3125 1760);
DISPLAY 0.617021 (-3125 1760);
PAINT ORANGE (-3125 1760);
FORCEPROP 2 LASTPROP $XRERR UNIQUE?
J 0
(-2495 1750);
DISPLAY 0.638298 (-2495 1750);
PAINT MONO (-2495 1750);
DISPLAY INVISIBLE (-2495 1750);
WIRE 16 -1 (-2525 1800)(-3475 1800);
FORCEPROP 0 LAST SIG_NAME TP_CPU1_UPI2_RSVD_CE12
J 0
(-3125 1810);
DISPLAY 0.617021 (-3125 1810);
PAINT ORANGE (-3125 1810);
FORCEPROP 2 LASTPROP $XRERR UNIQUE?
J 0
(-2495 1800);
DISPLAY 0.638298 (-2495 1800);
PAINT MONO (-2495 1800);
DISPLAY INVISIBLE (-2495 1800);
WIRE 16 -1 (-2525 1850)(-3475 1850);
FORCEPROP 0 LAST SIG_NAME TP_CPU1_UPI2_RSVD_CH11
J 0
(-3125 1860);
DISPLAY 0.617021 (-3125 1860);
PAINT ORANGE (-3125 1860);
FORCEPROP 2 LASTPROP $XRERR UNIQUE?
J 0
(-2495 1850);
DISPLAY 0.638298 (-2495 1850);
PAINT MONO (-2495 1850);
DISPLAY INVISIBLE (-2495 1850);
WIRE 16 -1 (-2525 1900)(-3475 1900);
FORCEPROP 0 LAST SIG_NAME TP_CPU1_UPI2_RSVD_CF13
J 0
(-3125 1910);
DISPLAY 0.617021 (-3125 1910);
PAINT ORANGE (-3125 1910);
FORCEPROP 2 LASTPROP $XRERR UNIQUE?
J 0
(-2495 1900);
DISPLAY 0.638298 (-2495 1900);
PAINT MONO (-2495 1900);
DISPLAY INVISIBLE (-2495 1900);
WIRE 16 -1 (-2525 1950)(-3475 1950);
FORCEPROP 0 LAST SIG_NAME TP_CPU1_UPI2_RSVD_CJ14
J 0
(-3125 1960);
DISPLAY 0.617021 (-3125 1960);
PAINT ORANGE (-3125 1960);
FORCEPROP 2 LASTPROP $XRERR UNIQUE?
J 0
(-2495 1950);
DISPLAY 0.638298 (-2495 1950);
PAINT MONO (-2495 1950);
DISPLAY INVISIBLE (-2495 1950);
WIRE 16 -1 (-2525 2000)(-3475 2000);
FORCEPROP 0 LAST SIG_NAME TP_CPU1_UPI2_RSVD_CM13
J 0
(-3125 2010);
DISPLAY 0.617021 (-3125 2010);
PAINT ORANGE (-3125 2010);
FORCEPROP 2 LASTPROP $XRERR UNIQUE?
J 0
(-2495 2000);
DISPLAY 0.638298 (-2495 2000);
PAINT MONO (-2495 2000);
DISPLAY INVISIBLE (-2495 2000);
WIRE 16 -1 (-2525 2750)(-3475 2750);
FORCEPROP 0 LAST SIG_NAME TP_CPU1_UPI2_RSVD_CA12
J 0
(-3125 2760);
DISPLAY 0.617021 (-3125 2760);
PAINT ORANGE (-3125 2760);
FORCEPROP 2 LASTPROP $XRERR UNIQUE?
J 0
(-2495 2750);
DISPLAY 0.638298 (-2495 2750);
PAINT MONO (-2495 2750);
DISPLAY INVISIBLE (-2495 2750);
WIRE 16 -1 (-2525 2800)(-3475 2800);
FORCEPROP 0 LAST SIG_NAME TP_CPU1_UPI2_RSVD_CB11
J 0
(-3125 2810);
DISPLAY 0.617021 (-3125 2810);
PAINT ORANGE (-3125 2810);
FORCEPROP 2 LASTPROP $XRERR UNIQUE?
J 0
(-2495 2800);
DISPLAY 0.638298 (-2495 2800);
PAINT MONO (-2495 2800);
DISPLAY INVISIBLE (-2495 2800);
WIRE 16 -1 (-2525 2850)(-3475 2850);
FORCEPROP 0 LAST SIG_NAME TP_CPU1_UPI2_RSVD_CD11
J 0
(-3125 2860);
DISPLAY 0.617021 (-3125 2860);
PAINT ORANGE (-3125 2860);
FORCEPROP 2 LASTPROP $XRERR UNIQUE?
J 0
(-2495 2850);
DISPLAY 0.638298 (-2495 2850);
PAINT MONO (-2495 2850);
DISPLAY INVISIBLE (-2495 2850);
WIRE 16 -1 (-2525 2900)(-3475 2900);
FORCEPROP 0 LAST SIG_NAME TP_CPU1_UPI2_RSVD_CF11
J 0
(-3125 2910);
DISPLAY 0.617021 (-3125 2910);
PAINT ORANGE (-3125 2910);
FORCEPROP 2 LASTPROP $XRERR UNIQUE?
J 0
(-2495 2900);
DISPLAY 0.638298 (-2495 2900);
PAINT MONO (-2495 2900);
DISPLAY INVISIBLE (-2495 2900);
WIRE 16 -1 (-2525 2950)(-3475 2950);
FORCEPROP 0 LAST SIG_NAME TP_CPU1_UPI2_RSVD_CG12
J 0
(-3125 2960);
DISPLAY 0.617021 (-3125 2960);
PAINT ORANGE (-3125 2960);
FORCEPROP 2 LASTPROP $XRERR UNIQUE?
J 0
(-2495 2950);
DISPLAY 0.638298 (-2495 2950);
PAINT MONO (-2495 2950);
DISPLAY INVISIBLE (-2495 2950);
WIRE 16 -1 (-2525 3000)(-3475 3000);
FORCEPROP 0 LAST SIG_NAME TP_CPU1_UPI2_RSVD_CH13
J 0
(-3125 3010);
DISPLAY 0.617021 (-3125 3010);
PAINT ORANGE (-3125 3010);
FORCEPROP 2 LASTPROP $XRERR UNIQUE?
J 0
(-2495 3000);
DISPLAY 0.638298 (-2495 3000);
PAINT MONO (-2495 3000);
DISPLAY INVISIBLE (-2495 3000);
WIRE 16 -1 (-2525 3050)(-3475 3050);
FORCEPROP 0 LAST SIG_NAME TP_CPU1_UPI2_RSVD_CK13
J 0
(-3125 3060);
DISPLAY 0.617021 (-3125 3060);
PAINT ORANGE (-3125 3060);
FORCEPROP 2 LASTPROP $XRERR UNIQUE?
J 0
(-2495 3050);
DISPLAY 0.638298 (-2495 3050);
PAINT MONO (-2495 3050);
DISPLAY INVISIBLE (-2495 3050);
WIRE 16 -1 (-2525 3150)(-3475 3150);
FORCEPROP 0 LAST SIG_NAME TP_CPU1_UPI2_RSVD_CV13
J 0
(-3125 3160);
DISPLAY 0.617021 (-3125 3160);
PAINT ORANGE (-3125 3160);
FORCEPROP 2 LASTPROP $XRERR UNIQUE?
J 0
(-2495 3150);
DISPLAY 0.638298 (-2495 3150);
PAINT MONO (-2495 3150);
DISPLAY INVISIBLE (-2495 3150);
WIRE 16 -1 (-2525 3200)(-3475 3200);
FORCEPROP 0 LAST SIG_NAME TP_CPU1_UPI2_RSVD_CW16
J 0
(-3125 3210);
DISPLAY 0.617021 (-3125 3210);
PAINT ORANGE (-3125 3210);
FORCEPROP 2 LASTPROP $XRERR UNIQUE?
J 0
(-2495 3200);
DISPLAY 0.638298 (-2495 3200);
PAINT MONO (-2495 3200);
DISPLAY INVISIBLE (-2495 3200);
WIRE 16 -1 (-2525 3250)(-3475 3250);
FORCEPROP 0 LAST SIG_NAME TP_CPU1_UPI2_RSVD_DB15
J 0
(-3125 3260);
DISPLAY 0.617021 (-3125 3260);
PAINT ORANGE (-3125 3260);
FORCEPROP 2 LASTPROP $XRERR UNIQUE?
J 0
(-2495 3250);
DISPLAY 0.638298 (-2495 3250);
PAINT MONO (-2495 3250);
DISPLAY INVISIBLE (-2495 3250);
WIRE 16 -1 (-2525 3300)(-3475 3300);
FORCEPROP 0 LAST SIG_NAME TP_CPU1_UPI2_RSVD_DD15
J 0
(-3125 3310);
DISPLAY 0.617021 (-3125 3310);
PAINT ORANGE (-3125 3310);
FORCEPROP 2 LASTPROP $XRERR UNIQUE?
J 0
(-2495 3300);
DISPLAY 0.638298 (-2495 3300);
PAINT MONO (-2495 3300);
DISPLAY INVISIBLE (-2495 3300);
WIRE 16 -1 (-2525 3350)(-3475 3350);
FORCEPROP 0 LAST SIG_NAME TP_CPU1_UPI2_RSVD_DE16
J 0
(-3125 3360);
DISPLAY 0.617021 (-3125 3360);
PAINT ORANGE (-3125 3360);
FORCEPROP 2 LASTPROP $XRERR UNIQUE?
J 0
(-2495 3350);
DISPLAY 0.638298 (-2495 3350);
PAINT MONO (-2495 3350);
DISPLAY INVISIBLE (-2495 3350);
WIRE 16 -1 (-2525 3400)(-3475 3400);
FORCEPROP 0 LAST SIG_NAME TP_CPU1_UPI2_RSVD_DF17
J 0
(-3125 3410);
DISPLAY 0.617021 (-3125 3410);
PAINT ORANGE (-3125 3410);
FORCEPROP 2 LASTPROP $XRERR UNIQUE?
J 0
(-2495 3400);
DISPLAY 0.638298 (-2495 3400);
PAINT MONO (-2495 3400);
DISPLAY INVISIBLE (-2495 3400);
WIRE 16 -1 (-2525 3450)(-3475 3450);
FORCEPROP 0 LAST SIG_NAME TP_CPU1_UPI2_RSVD_DH17
J 0
(-3125 3460);
DISPLAY 0.617021 (-3125 3460);
PAINT ORANGE (-3125 3460);
FORCEPROP 2 LASTPROP $XRERR UNIQUE?
J 0
(-2495 3450);
DISPLAY 0.638298 (-2495 3450);
PAINT MONO (-2495 3450);
DISPLAY INVISIBLE (-2495 3450);
WIRE 16 -1 (-2525 3500)(-3475 3500);
FORCEPROP 0 LAST SIG_NAME TP_CPU1_UPI2_RSVD_DJ18
J 0
(-3125 3510);
DISPLAY 0.617021 (-3125 3510);
PAINT ORANGE (-3125 3510);
FORCEPROP 2 LASTPROP $XRERR UNIQUE?
J 0
(-2495 3500);
DISPLAY 0.638298 (-2495 3500);
PAINT MONO (-2495 3500);
DISPLAY INVISIBLE (-2495 3500);
WIRE 16 -1 (-2525 3550)(-3475 3550);
FORCEPROP 0 LAST SIG_NAME TP_CPU1_UPI2_RSVD_DJ20
J 0
(-3125 3560);
DISPLAY 0.617021 (-3125 3560);
PAINT ORANGE (-3125 3560);
FORCEPROP 2 LASTPROP $XRERR UNIQUE?
J 0
(-2495 3550);
DISPLAY 0.638298 (-2495 3550);
PAINT MONO (-2495 3550);
DISPLAY INVISIBLE (-2495 3550);
WIRE 16 -1 (-2525 3600)(-3475 3600);
FORCEPROP 0 LAST SIG_NAME TP_CPU1_UPI2_RSVD_DK19
J 0
(-3125 3610);
DISPLAY 0.617021 (-3125 3610);
PAINT ORANGE (-3125 3610);
FORCEPROP 2 LASTPROP $XRERR UNIQUE?
J 0
(-2495 3600);
DISPLAY 0.638298 (-2495 3600);
PAINT MONO (-2495 3600);
DISPLAY INVISIBLE (-2495 3600);
WIRE 16 -1 (-2525 3650)(-3475 3650);
FORCEPROP 0 LAST SIG_NAME TP_CPU1_UPI2_RSVD_DN20
J 0
(-3125 3660);
DISPLAY 0.617021 (-3125 3660);
PAINT ORANGE (-3125 3660);
FORCEPROP 2 LASTPROP $XRERR UNIQUE?
J 0
(-2495 3650);
DISPLAY 0.638298 (-2495 3650);
PAINT MONO (-2495 3650);
DISPLAY INVISIBLE (-2495 3650);
WIRE 16 -1 (-2525 3700)(-3475 3700);
FORCEPROP 0 LAST SIG_NAME TP_CPU1_UPI2_RSVD_DP21
J 0
(-3125 3710);
DISPLAY 0.617021 (-3125 3710);
PAINT ORANGE (-3125 3710);
FORCEPROP 2 LASTPROP $XRERR UNIQUE?
J 0
(-2495 3700);
DISPLAY 0.638298 (-2495 3700);
PAINT MONO (-2495 3700);
DISPLAY INVISIBLE (-2495 3700);
WIRE 16 -1 (-2525 2050)(-3475 2050);
FORCEPROP 0 LAST SIG_NAME TP_CPU1_UPI2_RSVD_CU14
J 0
(-3125 2060);
DISPLAY 0.617021 (-3125 2060);
PAINT ORANGE (-3125 2060);
FORCEPROP 2 LASTPROP $XRERR UNIQUE?
J 0
(-2495 2050);
DISPLAY 0.638298 (-2495 2050);
PAINT MONO (-2495 2050);
DISPLAY INVISIBLE (-2495 2050);
WIRE 16 -1 (-2525 2100)(-3475 2100);
FORCEPROP 0 LAST SIG_NAME TP_CPU1_UPI2_RSVD_CW14
J 0
(-3125 2110);
DISPLAY 0.617021 (-3125 2110);
PAINT ORANGE (-3125 2110);
FORCEPROP 2 LASTPROP $XRERR UNIQUE?
J 0
(-2495 2100);
DISPLAY 0.638298 (-2495 2100);
PAINT MONO (-2495 2100);
DISPLAY INVISIBLE (-2495 2100);
WIRE 16 -1 (-2525 2150)(-3475 2150);
FORCEPROP 0 LAST SIG_NAME TP_CPU1_UPI2_RSVD_DA16
J 0
(-3125 2160);
DISPLAY 0.617021 (-3125 2160);
PAINT ORANGE (-3125 2160);
FORCEPROP 2 LASTPROP $XRERR UNIQUE?
J 0
(-2495 2150);
DISPLAY 0.638298 (-2495 2150);
PAINT MONO (-2495 2150);
DISPLAY INVISIBLE (-2495 2150);
WIRE 16 -1 (-2525 2200)(-3475 2200);
FORCEPROP 0 LAST SIG_NAME TP_CPU1_UPI2_RSVD_DC16
J 0
(-3125 2210);
DISPLAY 0.617021 (-3125 2210);
PAINT ORANGE (-3125 2210);
FORCEPROP 2 LASTPROP $XRERR UNIQUE?
J 0
(-2495 2200);
DISPLAY 0.638298 (-2495 2200);
PAINT MONO (-2495 2200);
DISPLAY INVISIBLE (-2495 2200);
WIRE 16 -1 (-2525 2250)(-3475 2250);
FORCEPROP 0 LAST SIG_NAME TP_CPU1_UPI2_RSVD_DF15
J 0
(-3125 2260);
DISPLAY 0.617021 (-3125 2260);
PAINT ORANGE (-3125 2260);
FORCEPROP 2 LASTPROP $XRERR UNIQUE?
J 0
(-2495 2250);
DISPLAY 0.638298 (-2495 2250);
PAINT MONO (-2495 2250);
DISPLAY INVISIBLE (-2495 2250);
WIRE 16 -1 (-2525 2300)(-3475 2300);
FORCEPROP 0 LAST SIG_NAME TP_CPU1_UPI2_RSVD_DD17
J 0
(-3125 2310);
DISPLAY 0.617021 (-3125 2310);
PAINT ORANGE (-3125 2310);
FORCEPROP 2 LASTPROP $XRERR UNIQUE?
J 0
(-2495 2300);
DISPLAY 0.638298 (-2495 2300);
PAINT MONO (-2495 2300);
DISPLAY INVISIBLE (-2495 2300);
WIRE 16 -1 (-2525 2350)(-3475 2350);
FORCEPROP 0 LAST SIG_NAME TP_CPU1_UPI2_RSVD_DG18
J 0
(-3125 2360);
DISPLAY 0.617021 (-3125 2360);
PAINT ORANGE (-3125 2360);
FORCEPROP 2 LASTPROP $XRERR UNIQUE?
J 0
(-2495 2350);
DISPLAY 0.638298 (-2495 2350);
PAINT MONO (-2495 2350);
DISPLAY INVISIBLE (-2495 2350);
WIRE 16 -1 (-2525 2400)(-3475 2400);
FORCEPROP 0 LAST SIG_NAME TP_CPU1_UPI2_RSVD_DK17
J 0
(-3125 2410);
DISPLAY 0.617021 (-3125 2410);
PAINT ORANGE (-3125 2410);
FORCEPROP 2 LASTPROP $XRERR UNIQUE?
J 0
(-2495 2400);
DISPLAY 0.638298 (-2495 2400);
PAINT MONO (-2495 2400);
DISPLAY INVISIBLE (-2495 2400);
WIRE 16 -1 (-2525 2450)(-3475 2450);
FORCEPROP 0 LAST SIG_NAME TP_CPU1_UPI2_RSVD_DH19
J 0
(-3125 2460);
DISPLAY 0.617021 (-3125 2460);
PAINT ORANGE (-3125 2460);
FORCEPROP 2 LASTPROP $XRERR UNIQUE?
J 0
(-2495 2450);
DISPLAY 0.638298 (-2495 2450);
PAINT MONO (-2495 2450);
DISPLAY INVISIBLE (-2495 2450);
WIRE 16 -1 (-2525 2500)(-3475 2500);
FORCEPROP 0 LAST SIG_NAME TP_CPU1_UPI2_RSVD_DG20
J 0
(-3125 2510);
DISPLAY 0.617021 (-3125 2510);
PAINT ORANGE (-3125 2510);
FORCEPROP 2 LASTPROP $XRERR UNIQUE?
J 0
(-2495 2500);
DISPLAY 0.638298 (-2495 2500);
PAINT MONO (-2495 2500);
DISPLAY INVISIBLE (-2495 2500);
WIRE 16 -1 (-2525 2550)(-3475 2550);
FORCEPROP 0 LAST SIG_NAME TP_CPU1_UPI2_RSVD_DL20
J 0
(-3125 2560);
DISPLAY 0.617021 (-3125 2560);
PAINT ORANGE (-3125 2560);
FORCEPROP 2 LASTPROP $XRERR UNIQUE?
J 0
(-2495 2550);
DISPLAY 0.638298 (-2495 2550);
PAINT MONO (-2495 2550);
DISPLAY INVISIBLE (-2495 2550);
WIRE 16 -1 (-2525 2600)(-3475 2600);
FORCEPROP 0 LAST SIG_NAME TP_CPU1_UPI2_RSVD_DM21
J 0
(-3125 2610);
DISPLAY 0.617021 (-3125 2610);
PAINT ORANGE (-3125 2610);
FORCEPROP 2 LASTPROP $XRERR UNIQUE?
J 0
(-2495 2600);
DISPLAY 0.638298 (-2495 2600);
PAINT MONO (-2495 2600);
DISPLAY INVISIBLE (-2495 2600);
WIRE 16 -1 (-2525 2650)(-3475 2650);
FORCEPROP 0 LAST SIG_NAME TP_CPU1_UPI2_RSVD_DT21
J 0
(-3125 2660);
DISPLAY 0.617021 (-3125 2660);
PAINT ORANGE (-3125 2660);
FORCEPROP 2 LASTPROP $XRERR UNIQUE?
J 0
(-2495 2650);
DISPLAY 0.638298 (-2495 2650);
PAINT MONO (-2495 2650);
DISPLAY INVISIBLE (-2495 2650);
DOT 1 (-6025 2850);
DOT 1 (-6025 2100);
DOT 1 (-6025 1700);
DOT 1 (-6025 1750);
DOT 1 (-6025 1800);
DOT 1 (-6025 1850);
DOT 1 (-6025 1900);
DOT 1 (-6025 1950);
DOT 1 (-6025 2000);
DOT 1 (-6025 2050);
DOT 1 (-6025 2150);
DOT 1 (-6025 2200);
DOT 1 (-6025 2250);
DOT 1 (-6025 2300);
DOT 1 (-6025 2350);
DOT 1 (-6025 2400);
DOT 1 (-6025 2450);
DOT 1 (-6025 2500);
DOT 1 (-6025 2550);
DOT 1 (-6025 2600);
DOT 1 (-6025 2650);
DOT 1 (-6025 2750);
DOT 1 (-6025 2800);
DOT 1 (-6025 2900);
DOT 1 (-6025 2950);
DOT 1 (-6025 3000);
DOT 1 (-6025 3050);
DOT 1 (-6025 3100);
DOT 1 (-6025 3150);
DOT 1 (-6025 3200);
DOT 1 (-6025 3250);
DOT 1 (-6025 3300);
DOT 1 (-6025 3350);
DOT 1 (-6025 3400);
DOT 1 (-6025 3450);
DOT 1 (-6025 3500);
DOT 1 (-6025 3550);
DOT 1 (-6025 3600);
DOT 1 (-6025 3650);
FORCENOTE
BOM_COST=PROC_SOCKET
(-7925 200) 0;
DISPLAY LEFT (-7925 200);
DISPLAY 1.723404 (-7925 200);
PAINT PURPLE (-7925 200);
FORCENOTE
ROOM=CPU1
(-7925 325) 0;
DISPLAY LEFT (-7925 325);
DISPLAY 1.723404 (-7925 325);
PAINT PURPLE (-7925 325);
QUIT
